(kicad_pcb
	(version 20241229)
	(generator "pcbnew")
	(generator_version "9.0")
	(general
		(thickness 1.63)
		(legacy_teardrops no)
	)
	(paper "A4")
	(title_block
		(title "CM4 Baseboard")
		(date "2026-01-05")
		(rev "1.1.1")
		(company "Antmicro Ltd")
		(comment 1 "www.antmicro.com")
		(comment 9 "footprints 279-281 of 506")
	)
	(layers
		(0 "F.Cu" signal)
		(4 "In1.Cu" power)
		(6 "In2.Cu" power)
		(8 "In3.Cu" signal)
		(10 "In4.Cu" signal)
		(2 "B.Cu" signal)
		(9 "F.Adhes" user "F.Adhesive")
		(11 "B.Adhes" user "B.Adhesive")
		(13 "F.Paste" user)
		(15 "B.Paste" user)
		(5 "F.SilkS" user "F.Silkscreen")
		(7 "B.SilkS" user "B.Silkscreen")
		(1 "F.Mask" user)
		(3 "B.Mask" user)
		(17 "Dwgs.User" user "User.Drawings")
		(19 "Cmts.User" user "User.Comments")
		(21 "Eco1.User" user "User.Eco1")
		(23 "Eco2.User" user "User.Eco2")
		(25 "Edge.Cuts" user)
		(27 "Margin" user)
		(31 "F.CrtYd" user "F.Courtyard")
		(29 "B.CrtYd" user "B.Courtyard")
		(35 "F.Fab" user)
		(33 "B.Fab" user)
	)
	(footprint "antmicro-footprints:Spacer_Drill3.7mm_H3mm_9774030151R"
		(layer "F.Cu")
		(at 80.520961 176.314 -90)
		(descr "Spacer M=3 h=3mm fi=5.1mm")
		(property "Reference" "H202"
			(at -0.1575 -4.087001 90)
			(layer "F.SilkS")
			(hide yes)
			(effects
				(font
					(size 0.7 0.7)
					(thickness 0.15)
				)
				(justify right bottom)
			)
		)
		(property "Value" "Spacer_Drill3.7mm_H3mm_9774030151R"
			(at 0 4 90)
			(layer "F.Fab")
			(effects
				(font
					(size 0.7 0.7)
					(thickness 0.15)
				)
				(justify right bottom)
			)
		)
		(property "Datasheet" "https://www.we-online.com/catalog/datasheet/9774030151.pdf"
			(at 0 0 270)
			(layer "F.Fab")
			(hide yes)
			(effects
				(font
					(size 1.27 1.27)
					(thickness 0.15)
				)
			)
		)
		(property "Manufacturer" "Würth Elektronik"
			(at 0 0 270)
			(unlocked yes)
			(layer "F.Fab")
			(hide yes)
			(effects
				(font
					(size 1 1)
					(thickness 0.15)
				)
			)
		)
		(property "MPN" "9774030151R"
			(at 0 0 270)
			(unlocked yes)
			(layer "F.Fab")
			(hide yes)
			(effects
				(font
					(size 1 1)
					(thickness 0.15)
				)
			)
		)
		(property "Author" "Antmicro"
			(at 0 0 270)
			(unlocked yes)
			(layer "F.Fab")
			(hide yes)
			(effects
				(font
					(size 1 1)
					(thickness 0.15)
				)
			)
		)
		(property "License" "Apache-2.0"
			(at 0 0 270)
			(unlocked yes)
			(layer "F.Fab")
			(hide yes)
			(effects
				(font
					(size 1 1)
					(thickness 0.15)
				)
			)
		)
		(sheetname "/Compute module/")
		(sheetfile "compute-module.kicad_sch")
		(solder_paste_margin_ratio -1)
		(attr smd)
		(fp_circle
			(center 0 0)
			(end 3.05 0)
			(stroke
				(width 0.05)
				(type solid)
			)
			(fill no)
			(layer "F.CrtYd")
		)
		(fp_circle
			(center 0 0)
			(end 2.6 0)
			(stroke
				(width 0.15)
				(type solid)
			)
			(fill no)
			(layer "F.Fab")
		)
		(fp_text user "${REFERENCE}"
			(at -9.6 6.5 270)
			(layer "F.Fab")
			(effects
				(font
					(size 0.7 0.7)
					(thickness 0.15)
				)
				(justify left bottom)
			)
		)
		(fp_text user "Author: Antmicro"
			(at -9.6 7.7 270)
			(layer "F.Fab")
			(effects
				(font
					(size 0.7 0.7)
					(thickness 0.15)
				)
				(justify left bottom)
			)
		)
		(fp_text user "License: Apache-2.0"
			(at -9.6 8.9 270)
			(layer "F.Fab")
			(effects
				(font
					(size 0.7 0.7)
					(thickness 0.15)
				)
				(justify left bottom)
			)
		)
		(pad "" smd custom
			(at -1.7 -1.7 270)
			(size 0.62 0.62)
			(layers "F.Paste")
			(thermal_bridge_angle 90)
			(options
				(clearance outline)
				(anchor circle)
			)
			(primitives
				(gr_arc
					(start -0.250195 1.279127)
					(mid 0.285453 0.294389)
					(end 1.266786 -0.24747)
					(width 0.2)
				)
				(gr_arc
					(start -0.34334 1.279127)
					(mid 0.218448 0.232561)
					(end 1.259603 -0.339191)
					(width 0.2)
				)
				(gr_arc
					(start -0.436309 1.279127)
					(mid 0.152481 0.169693)
					(end 1.255279 -0.431435)
					(width 0.2)
				)
				(gr_arc
					(start -0.529126 1.279127)
					(mid 0.087542 0.105784)
					(end 1.253811 -0.524161)
					(width 0.2)
				)
				(gr_arc
					(start -0.621807 1.279127)
					(mid 0.0309 0.033527)
					(end 1.275473 -0.621136)
					(width 0.2)
				)
				(gr_arc
					(start -0.71437 1.279127)
					(mid -0.037758 -0.026651)
					(end 1.263664 -0.711602)
					(width 0.2)
				)
				(gr_arc
					(start -0.806826 1.279127)
					(mid -0.105837 -0.087395)
					(end 1.253435 -0.802342)
					(width 0.2)
				)
				(gr_arc
					(start -0.899187 1.279127)
					(mid -0.165236 -0.156885)
					(end 1.267475 -0.897258)
					(width 0.2)
				)
				(gr_arc
					(start -0.991463 1.279127)
					(mid -0.228522 -0.222449)
					(end 1.270645 -0.990112)
					(width 0.2)
				)
				(gr_arc
					(start -1.083663 1.279127)
					(mid -0.294507 -0.285313)
					(end 1.266278 -1.081674)
					(width 0.2)
				)
				(gr_line
					(start 1.279127 -0.250195)
					(end 1.279127 -1.083663)
					(width 0.2)
				)
				(gr_line
					(start -0.250195 1.279127)
					(end -1.083663 1.279127)
					(width 0.2)
				)
			)
		)
		(pad "" smd custom
			(at -1.7 1.7)
			(size 0.62 0.62)
			(layers "F.Paste")
			(thermal_bridge_angle 90)
			(options
				(clearance outline)
				(anchor circle)
			)
			(primitives
				(gr_arc
					(start -0.250195 1.279127)
					(mid 0.285453 0.294389)
					(end 1.266786 -0.24747)
					(width 0.2)
				)
				(gr_arc
					(start -0.34334 1.279127)
					(mid 0.218448 0.232561)
					(end 1.259603 -0.339191)
					(width 0.2)
				)
				(gr_arc
					(start -0.436309 1.279127)
					(mid 0.152481 0.169693)
					(end 1.255279 -0.431435)
					(width 0.2)
				)
				(gr_arc
					(start -0.529126 1.279127)
					(mid 0.087542 0.105784)
					(end 1.253811 -0.524161)
					(width 0.2)
				)
				(gr_arc
					(start -0.621807 1.279127)
					(mid 0.0309 0.033527)
					(end 1.275473 -0.621136)
					(width 0.2)
				)
				(gr_arc
					(start -0.71437 1.279127)
					(mid -0.037758 -0.026651)
					(end 1.263664 -0.711602)
					(width 0.2)
				)
				(gr_arc
					(start -0.806826 1.279127)
					(mid -0.105837 -0.087395)
					(end 1.253435 -0.802342)
					(width 0.2)
				)
				(gr_arc
					(start -0.899187 1.279127)
					(mid -0.165236 -0.156885)
					(end 1.267475 -0.897258)
					(width 0.2)
				)
				(gr_arc
					(start -0.991463 1.279127)
					(mid -0.228522 -0.222449)
					(end 1.270645 -0.990112)
					(width 0.2)
				)
				(gr_arc
					(start -1.083663 1.279127)
					(mid -0.294507 -0.285313)
					(end 1.266278 -1.081674)
					(width 0.2)
				)
				(gr_line
					(start 1.279127 -0.250195)
					(end 1.279127 -1.083663)
					(width 0.2)
				)
				(gr_line
					(start -0.250195 1.279127)
					(end -1.083663 1.279127)
					(width 0.2)
				)
			)
		)
		(pad "" smd custom
			(at 1.7 -1.7 180)
			(size 0.62 0.62)
			(layers "F.Paste")
			(thermal_bridge_angle 90)
			(options
				(clearance outline)
				(anchor circle)
			)
			(primitives
				(gr_arc
					(start -0.250195 1.279127)
					(mid 0.285453 0.294389)
					(end 1.266786 -0.24747)
					(width 0.2)
				)
				(gr_arc
					(start -0.34334 1.279127)
					(mid 0.218448 0.232561)
					(end 1.259603 -0.339191)
					(width 0.2)
				)
				(gr_arc
					(start -0.436309 1.279127)
					(mid 0.152481 0.169693)
					(end 1.255279 -0.431435)
					(width 0.2)
				)
				(gr_arc
					(start -0.529126 1.279127)
					(mid 0.087542 0.105784)
					(end 1.253811 -0.524161)
					(width 0.2)
				)
				(gr_arc
					(start -0.621807 1.279127)
					(mid 0.0309 0.033527)
					(end 1.275473 -0.621136)
					(width 0.2)
				)
				(gr_arc
					(start -0.71437 1.279127)
					(mid -0.037758 -0.026651)
					(end 1.263664 -0.711602)
					(width 0.2)
				)
				(gr_arc
					(start -0.806826 1.279127)
					(mid -0.105837 -0.087395)
					(end 1.253435 -0.802342)
					(width 0.2)
				)
				(gr_arc
					(start -0.899187 1.279127)
					(mid -0.165236 -0.156885)
					(end 1.267475 -0.897258)
					(width 0.2)
				)
				(gr_arc
					(start -0.991463 1.279127)
					(mid -0.228522 -0.222449)
					(end 1.270645 -0.990112)
					(width 0.2)
				)
				(gr_arc
					(start -1.083663 1.279127)
					(mid -0.294507 -0.285313)
					(end 1.266278 -1.081674)
					(width 0.2)
				)
				(gr_line
					(start 1.279127 -0.250195)
					(end 1.279127 -1.083663)
					(width 0.2)
				)
				(gr_line
					(start -0.250195 1.279127)
					(end -1.083663 1.279127)
					(width 0.2)
				)
			)
		)
		(pad "" smd custom
			(at 1.7 1.7 90)
			(size 0.62 0.62)
			(layers "F.Paste")
			(thermal_bridge_angle 90)
			(options
				(clearance outline)
				(anchor circle)
			)
			(primitives
				(gr_arc
					(start -0.250195 1.279127)
					(mid 0.285453 0.294389)
					(end 1.266786 -0.24747)
					(width 0.2)
				)
				(gr_arc
					(start -0.34334 1.279127)
					(mid 0.218448 0.232561)
					(end 1.259603 -0.339191)
					(width 0.2)
				)
				(gr_arc
					(start -0.436309 1.279127)
					(mid 0.152481 0.169693)
					(end 1.255279 -0.431435)
					(width 0.2)
				)
				(gr_arc
					(start -0.529126 1.279127)
					(mid 0.087542 0.105784)
					(end 1.253811 -0.524161)
					(width 0.2)
				)
				(gr_arc
					(start -0.621807 1.279127)
					(mid 0.0309 0.033527)
					(end 1.275473 -0.621136)
					(width 0.2)
				)
				(gr_arc
					(start -0.71437 1.279127)
					(mid -0.037758 -0.026651)
					(end 1.263664 -0.711602)
					(width 0.2)
				)
				(gr_arc
					(start -0.806826 1.279127)
					(mid -0.105837 -0.087395)
					(end 1.253435 -0.802342)
					(width 0.2)
				)
				(gr_arc
					(start -0.899187 1.279127)
					(mid -0.165236 -0.156885)
					(end 1.267475 -0.897258)
					(width 0.2)
				)
				(gr_arc
					(start -0.991463 1.279127)
					(mid -0.228522 -0.222449)
					(end 1.270645 -0.990112)
					(width 0.2)
				)
				(gr_arc
					(start -1.083663 1.279127)
					(mid -0.294507 -0.285313)
					(end 1.266278 -1.081674)
					(width 0.2)
				)
				(gr_line
					(start 1.279127 -0.250195)
					(end 1.279127 -1.083663)
					(width 0.2)
				)
				(gr_line
					(start -0.250195 1.279127)
					(end -1.083663 1.279127)
					(width 0.2)
				)
			)
		)
		(pad "1" thru_hole circle
			(at 0 0 270)
			(size 6 6)
			(drill 3.7)
			(layers "*.Cu" "*.Mask")
			(remove_unused_layers no)
			(net 3 "GND")
			(pintype "passive")
		)
	)
	(footprint "antmicro-footprints:C_0402_1005Metric"
		(layer "F.Cu")
		(at 91.692962 148.2415 90)
		(descr "Capacitor SMD 0402")
		(tags "capacitor SMD 0402")
		(property "Reference" "C927"
			(at -3.755 0.135 90)
			(layer "F.SilkS")
			(effects
				(font
					(size 0.7 0.7)
					(thickness 0.15)
				)
				(justify left bottom)
			)
		)
		(property "Value" "C_18p_0402"
			(at -1.022927 2.155213 90)
			(layer "F.Fab")
			(effects
				(font
					(size 0.7 0.7)
					(thickness 0.15)
				)
				(justify left bottom)
			)
		)
		(property "Datasheet" "https://product.samsungsem.com/mlcc/CL05C180JB51PN.do"
			(at 0 0 90)
			(layer "F.Fab")
			(hide yes)
			(effects
				(font
					(size 1.27 1.27)
					(thickness 0.15)
				)
			)
		)
		(property "Manufacturer" "Samsung Electro-Mechanics"
			(at 0 0 90)
			(unlocked yes)
			(layer "F.Fab")
			(hide yes)
			(effects
				(font
					(size 1 1)
					(thickness 0.15)
				)
			)
		)
		(property "MPN" "CL05C180JB51PNC"
			(at 0 0 90)
			(unlocked yes)
			(layer "F.Fab")
			(hide yes)
			(effects
				(font
					(size 1 1)
					(thickness 0.15)
				)
			)
		)
		(property "Val" "18p"
			(at 0 0 90)
			(unlocked yes)
			(layer "F.Fab")
			(hide yes)
			(effects
				(font
					(size 1 1)
					(thickness 0.15)
				)
			)
		)
		(property "License" "Apache-2.0"
			(at 0 0 90)
			(unlocked yes)
			(layer "F.Fab")
			(hide yes)
			(effects
				(font
					(size 1 1)
					(thickness 0.15)
				)
			)
		)
		(property "Author" "Antmicro"
			(at 0 0 90)
			(unlocked yes)
			(layer "F.Fab")
			(hide yes)
			(effects
				(font
					(size 1 1)
					(thickness 0.15)
				)
			)
		)
		(property "Voltage" ""
			(at 0 0 90)
			(unlocked yes)
			(layer "F.Fab")
			(hide yes)
			(effects
				(font
					(size 1 1)
					(thickness 0.15)
				)
			)
		)
		(property "Dielectric" ""
			(at 0 0 90)
			(unlocked yes)
			(layer "F.Fab")
			(hide yes)
			(effects
				(font
					(size 1 1)
					(thickness 0.15)
				)
			)
		)
		(sheetname "/USB/")
		(sheetfile "usb.kicad_sch")
		(attr smd)
		(fp_rect
			(start -0.925 -0.47)
			(end 0.925 0.47)
			(stroke
				(width 0.05)
				(type default)
			)
			(fill no)
			(layer "F.CrtYd")
		)
		(fp_line
			(start 0.504 -0.25)
			(end 0.504 0.248)
			(stroke
				(width 0.15)
				(type solid)
			)
			(layer "F.Fab")
		)
		(fp_line
			(start -0.494 -0.25)
			(end 0.504 -0.25)
			(stroke
				(width 0.15)
				(type solid)
			)
			(layer "F.Fab")
		)
		(fp_line
			(start 0.504 0.248)
			(end -0.494 0.248)
			(stroke
				(width 0.15)
				(type solid)
			)
			(layer "F.Fab")
		)
		(fp_line
			(start -0.494 0.248)
			(end -0.494 -0.25)
			(stroke
				(width 0.15)
				(type solid)
			)
			(layer "F.Fab")
		)
		(fp_text user "Author: Antmicro"
			(at -0.939 3.399 90)
			(layer "F.Fab")
			(effects
				(font
					(size 0.7 0.7)
					(thickness 0.15)
				)
				(justify left bottom)
			)
		)
		(fp_text user "License: Apache-2.0"
			(at -0.939 5.799 90)
			(layer "F.Fab")
			(effects
				(font
					(size 0.7 0.7)
					(thickness 0.15)
				)
				(justify left bottom)
			)
		)
		(fp_text user "${REFERENCE}"
			(at -0.939 4.599 90)
			(layer "F.Fab")
			(effects
				(font
					(size 0.7 0.7)
					(thickness 0.15)
				)
				(justify left bottom)
			)
		)
		(pad "1" smd roundrect
			(at -0.48 0 90)
			(size 0.59 0.64)
			(layers "F.Cu" "F.Mask" "F.Paste")
			(roundrect_rratio 0.25)
			(net 115 "Net-(U905-OSCO)")
			(pintype "passive")
		)
		(pad "2" smd roundrect
			(at 0.48 0 90)
			(size 0.59 0.64)
			(layers "F.Cu" "F.Mask" "F.Paste")
			(roundrect_rratio 0.25)
			(net 3 "GND")
			(pintype "passive")
		)
	)
	(footprint "antmicro-footprints:SOIC-8_3.9x4.9x1.75mm_P1.27mm"
		(layer "F.Cu")
		(at 80.617962 134.457236)
		(property "Reference" "U902"
			(at -3.84 3.529264 0)
			(layer "F.SilkS")
			(effects
				(font
					(size 0.7 0.7)
					(thickness 0.15)
				)
				(justify left bottom)
			)
		)
		(property "Value" "93AA66C_SOIC"
			(at 0 3.65 0)
			(layer "F.Fab")
			(effects
				(font
					(size 0.7 0.7)
					(thickness 0.15)
				)
				(justify left bottom)
			)
		)
		(property "Datasheet" "https://ww1.microchip.com/downloads/aemDocuments/documents/MPD/ProductDocuments/DataSheets/93AA66X-93LC66X-93C66X-4-Kbit-Microwire-Compatible-Serial-EEPROM-Data-Sheet.pdf"
			(at 0 0 0)
			(layer "F.Fab")
			(hide yes)
			(effects
				(font
					(size 1.27 1.27)
					(thickness 0.15)
				)
			)
		)
		(property "MPN" "93AA66C-I/SN"
			(at 0 0 0)
			(unlocked yes)
			(layer "F.Fab")
			(hide yes)
			(effects
				(font
					(size 1 1)
					(thickness 0.15)
				)
			)
		)
		(property "Manufacturer" "Microchip Technology"
			(at 0 0 0)
			(unlocked yes)
			(layer "F.Fab")
			(hide yes)
			(effects
				(font
					(size 1 1)
					(thickness 0.15)
				)
			)
		)
		(property "Author" "Antmicro"
			(at 0 0 0)
			(unlocked yes)
			(layer "F.Fab")
			(hide yes)
			(effects
				(font
					(size 1 1)
					(thickness 0.15)
				)
			)
		)
		(property "License" "Apache-2.0"
			(at 0 0 0)
			(unlocked yes)
			(layer "F.Fab")
			(hide yes)
			(effects
				(font
					(size 1 1)
					(thickness 0.15)
				)
			)
		)
		(property ki_fp_filters "DIP*W7.62mm* SOIC*3.9x4.9mm*")
		(sheetname "/USB/")
		(sheetfile "usb.kicad_sch")
		(attr smd)
		(fp_line
			(start -1.95 -2.452)
			(end 1.95 -2.45)
			(stroke
				(width 0.15)
				(type solid)
			)
			(layer "F.SilkS")
		)
		(fp_line
			(start -1.95 2.45)
			(end 1.95 2.45)
			(stroke
				(width 0.15)
				(type solid)
			)
			(layer "F.SilkS")
		)
		(fp_circle
			(center -2.4 -2.45)
			(end -2.35 -2.4)
			(stroke
				(width 0.15)
				(type solid)
			)
			(fill yes)
			(layer "F.SilkS")
		)
		(fp_rect
			(start -3.625 -2.7)
			(end 3.625 2.7)
			(stroke
				(width 0.05)
				(type solid)
			)
			(fill no)
			(layer "F.CrtYd")
		)
		(fp_line
			(start -1.95 -1.18)
			(end -0.683 -2.452)
			(stroke
				(width 0.15)
				(type solid)
			)
			(layer "F.Fab")
		)
		(fp_line
			(start -1.95 2.45)
			(end -1.95 -1.18)
			(stroke
				(width 0.15)
				(type solid)
			)
			(layer "F.Fab")
		)
		(fp_line
			(start -0.683 -2.452)
			(end 1.949 -2.452)
			(stroke
				(width 0.15)
				(type solid)
			)
			(layer "F.Fab")
		)
		(fp_line
			(start 1.949 -2.452)
			(end 1.949 2.45)
			(stroke
				(width 0.15)
				(type solid)
			)
			(layer "F.Fab")
		)
		(fp_line
			(start 1.949 2.45)
			(end -1.95 2.45)
			(stroke
				(width 0.15)
				(type solid)
			)
			(layer "F.Fab")
		)
		(fp_text user "License: Apache-2.0"
			(at -3.476 5.099 0)
			(layer "F.Fab")
			(effects
				(font
					(size 0.7 0.7)
					(thickness 0.15)
				)
				(justify left bottom)
			)
		)
		(fp_text user "Author: Antmicro"
			(at -3.476 6.099 0)
			(layer "F.Fab")
			(effects
				(font
					(size 0.7 0.7)
					(thickness 0.15)
				)
				(justify left bottom)
			)
		)
		(fp_text user "${REFERENCE}"
			(at -3.476 7.099 0)
			(layer "F.Fab")
			(effects
				(font
					(size 0.7 0.7)
					(thickness 0.15)
				)
				(justify left bottom)
			)
		)
		(pad "1" smd roundrect
			(at -2.714 -1.905 90)
			(size 0.65 1.525)
			(layers "F.Cu" "F.Mask" "F.Paste")
			(roundrect_rratio 0.25)
			(net 283 "/USB/EECS")
			(pinfunction "CS")
			(pintype "input")
		)
		(pad "2" smd roundrect
			(at -2.714 -0.635 90)
			(size 0.65 1.525)
			(layers "F.Cu" "F.Mask" "F.Paste")
			(roundrect_rratio 0.25)
			(net 282 "/USB/EECLK")
			(pinfunction "CLK")
			(pintype "input")
		)
		(pad "3" smd roundrect
			(at -2.714 0.632 90)
			(size 0.65 1.525)
			(layers "F.Cu" "F.Mask" "F.Paste")
			(roundrect_rratio 0.25)
			(net 281 "/USB/EEDATA")
			(pinfunction "DI")
			(pintype "input")
		)
		(pad "4" smd roundrect
			(at -2.714 1.902 90)
			(size 0.65 1.525)
			(layers "F.Cu" "F.Mask" "F.Paste")
			(roundrect_rratio 0.25)
			(net 377 "Net-(U902-DO)")
			(pinfunction "DO")
			(pintype "tri_state")
		)
		(pad "5" smd roundrect
			(at 2.712 1.902 90)
			(size 0.65 1.525)
			(layers "F.Cu" "F.Mask" "F.Paste")
			(roundrect_rratio 0.25)
			(net 3 "GND")
			(pinfunction "GND")
			(pintype "power_in")
		)
		(pad "6" smd roundrect
			(at 2.712 0.632 90)
			(size 0.65 1.525)
			(layers "F.Cu" "F.Mask" "F.Paste")
			(roundrect_rratio 0.25)
			(net 27 "/USB/USB_3V3")
			(pinfunction "ORG")
			(pintype "input")
		)
		(pad "7" smd roundrect
			(at 2.712 -0.635 90)
			(size 0.65 1.525)
			(layers "F.Cu" "F.Mask" "F.Paste")
			(roundrect_rratio 0.25)
			(net 406 "unconnected-(U902-NC-Pad7)")
			(pinfunction "NC")
			(pintype "no_connect")
		)
		(pad "8" smd roundrect
			(at 2.712 -1.905 90)
			(size 0.65 1.525)
			(layers "F.Cu" "F.Mask" "F.Paste")
			(roundrect_rratio 0.25)
			(net 27 "/USB/USB_3V3")
			(pinfunction "VCC")
			(pintype "power_in")
		)
	)
)
